(kicad_pcb
	(version 20260206)
	(generator "pcbnew")
	(generator_version "10.0")
	(general
		(thickness 1.6)
		(legacy_teardrops no)
	)
	(paper "A4")
	(title_block
		(title "Bryce Canyon_SCC_16316-1_OCP.brd")
		(comment 1 "Bryce Canyon / footprints 518-524 of 1561")
	)
	(layers
		(0 "F.Cu" signal "TOP")
		(4 "In1.Cu" signal "L2GND")
		(6 "In2.Cu" signal "L3")
		(8 "In3.Cu" signal "L4VCC")
		(10 "In4.Cu" signal "L5VCC")
		(12 "In5.Cu" signal "L6")
		(14 "In6.Cu" signal "L7GND")
		(2 "B.Cu" signal "BOTTOM")
		(9 "F.Adhes" user "F.Adhesive")
		(11 "B.Adhes" user "B.Adhesive")
		(13 "F.Paste" user "Package Geometry/Pastemask Top")
		(15 "B.Paste" user "Package Geometry/Pastemask Bottom")
		(5 "F.SilkS" user "Ref Des/Silkscreen Top")
		(7 "B.SilkS" user "Ref Des/Silkscreen Bottom")
		(1 "F.Mask" user "Board Geometry/Soldermask Top")
		(3 "B.Mask" user "Board Geometry/Soldermask Bottom")
		(17 "Dwgs.User" user "User.Drawings")
		(19 "Cmts.User" user "User.Comments")
		(21 "Eco1.User" user "User.Eco1")
		(23 "Eco2.User" user "User.Eco2")
		(25 "Edge.Cuts" user "Board Geometry/Outline")
		(27 "Margin" user)
		(31 "F.CrtYd" user "Package Geometry/Place Bound Top")
		(29 "B.CrtYd" user "Package Geometry/Place Bound Bottom")
		(35 "F.Fab" user "Ref Des/Assembly Top")
		(33 "B.Fab" user "Ref Des/Assembly Bottom")
	)
	(footprint ""
		(layer "F.Cu")
		(at 41.0972 -27.6987 90)
		(property "Reference" "R386"
			(at 0 0 90)
			(layer "F.SilkS")
			(hide yes)
			(effects
				(font
					(size 1.27 1.27)
				)
			)
		)
		(property "Value" "0R2J-2-GP"
			(at 0.064008 -3.993896 90)
			(unlocked yes)
			(layer "F.Fab")
			(hide yes)
			(effects
				(font
					(size 1.016 1.016)
					(thickness 0.1524)
				)
			)
		)
		(property "Device Type" "R402H16"
			(at 0.064008 -5.517896 90)
			(unlocked yes)
			(layer "F.Fab")
			(hide yes)
			(effects
				(font
					(size 1.016 1.016)
					(thickness 0.1524)
				)
			)
		)
		(duplicate_pad_numbers_are_jumpers no)
		(fp_line
			(start 0.508 -0.9398)
			(end -0.508 -0.9398)
			(stroke
				(width 0.1524)
				(type default)
			)
			(layer "F.SilkS")
		)
		(fp_line
			(start -0.508 -0.9398)
			(end -0.508 0.9398)
			(stroke
				(width 0.1524)
				(type default)
			)
			(layer "F.SilkS")
		)
		(fp_rect
			(start -0.508 0.9398)
			(end 0.508 -0.9398)
			(stroke
				(width 0)
				(type default)
			)
			(fill no)
			(layer "F.CrtYd")
		)
		(fp_rect
			(start -0.508 0.9398)
			(end 0.508 -0.9398)
			(stroke
				(width 0)
				(type default)
			)
			(fill no)
			(layer "F.Fab")
		)
		(pad "1" smd custom
			(at 0 -0.4445 90)
			(size 0.1397 0.1397)
			(layers "F.Cu" "F.Mask" "F.Paste")
			(net "P0V9_PG")
			(options
				(clearance outline)
				(anchor circle)
			)
			(primitives
				(gr_poly
					(pts
						(arc
							(start -0.1778 -0.2794)
							(mid -0.249642 -0.249642)
							(end -0.2794 -0.1778)
						)
						(arc
							(start -0.2794 0.1778)
							(mid -0.249642 0.249642)
							(end -0.1778 0.2794)
						)
						(arc
							(start 0.1778 0.2794)
							(mid 0.249642 0.249642)
							(end 0.2794 0.1778)
						)
						(arc
							(start 0.2794 -0.1778)
							(mid 0.249642 -0.249642)
							(end 0.1778 -0.2794)
						)
					)
					(width 0)
					(fill yes)
				)
			)
		)
		(pad "2" smd custom
			(at 0 0.4445 90)
			(size 0.1397 0.1397)
			(layers "F.Cu" "F.Mask" "F.Paste")
			(net "P0V9_U8_PG")
			(options
				(clearance outline)
				(anchor circle)
			)
			(primitives
				(gr_poly
					(pts
						(arc
							(start -0.1778 -0.2794)
							(mid -0.249642 -0.249642)
							(end -0.2794 -0.1778)
						)
						(arc
							(start -0.2794 0.1778)
							(mid -0.249642 0.249642)
							(end -0.1778 0.2794)
						)
						(arc
							(start 0.1778 0.2794)
							(mid 0.249642 0.249642)
							(end 0.2794 0.1778)
						)
						(arc
							(start 0.2794 -0.1778)
							(mid 0.249642 -0.249642)
							(end 0.1778 -0.2794)
						)
					)
					(width 0)
					(fill yes)
				)
			)
		)
	)
	(footprint ""
		(layer "F.Cu")
		(at 18.6944 -56.134 -90)
		(property "Reference" "C648"
			(at 0 0 270)
			(layer "F.SilkS")
			(hide yes)
			(effects
				(font
					(size 1.27 1.27)
				)
			)
		)
		(property "Value" "SCD01U25V2KX-3GP"
			(at 1.1811 -2.7051 270)
			(unlocked yes)
			(layer "F.Fab")
			(hide yes)
			(effects
				(font
					(size 1.016 1.016)
					(thickness 0.1524)
				)
			)
		)
		(property "Device Type" "C402H22"
			(at 1.1811 -4.2291 270)
			(unlocked yes)
			(layer "F.Fab")
			(hide yes)
			(effects
				(font
					(size 1.016 1.016)
					(thickness 0.1524)
				)
			)
		)
		(duplicate_pad_numbers_are_jumpers no)
		(fp_rect
			(start -0.4318 0.9525)
			(end 0.4318 -0.9525)
			(stroke
				(width 0)
				(type default)
			)
			(fill no)
			(layer "F.CrtYd")
		)
		(fp_rect
			(start -0.4318 0.9525)
			(end 0.4318 -0.9525)
			(stroke
				(width 0)
				(type default)
			)
			(fill no)
			(layer "F.Fab")
		)
		(pad "1" smd custom
			(at 0 -0.4445 270)
			(size 0.1524 0.1524)
			(layers "F.Cu" "F.Mask" "F.Paste")
			(net "AGND_CURRENT_MON")
			(options
				(clearance outline)
				(anchor circle)
			)
			(primitives
				(gr_poly
					(pts
						(arc
							(start 0.3048 -0.2032)
							(mid 0.275042 -0.275042)
							(end 0.2032 -0.3048)
						)
						(arc
							(start -0.2032 -0.3048)
							(mid -0.275042 -0.275042)
							(end -0.3048 -0.2032)
						)
						(arc
							(start -0.3048 0.2032)
							(mid -0.275042 0.275042)
							(end -0.2032 0.3048)
						)
						(arc
							(start 0.2032 0.3048)
							(mid 0.275042 0.275042)
							(end 0.3048 0.2032)
						)
					)
					(width 0)
					(fill yes)
				)
			)
		)
		(pad "2" smd custom
			(at 0 0.4445 270)
			(size 0.1524 0.1524)
			(layers "F.Cu" "F.Mask" "F.Paste")
			(net "MB0_TIME_R")
			(options
				(clearance outline)
				(anchor circle)
			)
			(primitives
				(gr_poly
					(pts
						(arc
							(start 0.3048 -0.2032)
							(mid 0.275042 -0.275042)
							(end 0.2032 -0.3048)
						)
						(arc
							(start -0.2032 -0.3048)
							(mid -0.275042 -0.275042)
							(end -0.3048 -0.2032)
						)
						(arc
							(start -0.3048 0.2032)
							(mid -0.275042 0.275042)
							(end -0.2032 0.3048)
						)
						(arc
							(start 0.2032 0.3048)
							(mid 0.275042 0.275042)
							(end 0.3048 0.2032)
						)
					)
					(width 0)
					(fill yes)
				)
			)
		)
	)
	(footprint ""
		(layer "F.Cu")
		(at 11.5316 -93.3196 90)
		(property "Reference" "R434"
			(at 0 0 90)
			(layer "F.SilkS")
			(hide yes)
			(effects
				(font
					(size 1.27 1.27)
				)
			)
		)
		(property "Value" "0R2J-2-GP"
			(at 0.064008 -3.993896 90)
			(unlocked yes)
			(layer "F.Fab")
			(hide yes)
			(effects
				(font
					(size 1.016 1.016)
					(thickness 0.1524)
				)
			)
		)
		(property "Device Type" "R402H16"
			(at 0.064008 -5.517896 90)
			(unlocked yes)
			(layer "F.Fab")
			(hide yes)
			(effects
				(font
					(size 1.016 1.016)
					(thickness 0.1524)
				)
			)
		)
		(duplicate_pad_numbers_are_jumpers no)
		(fp_line
			(start 0.508 -0.9398)
			(end -0.508 -0.9398)
			(stroke
				(width 0.1524)
				(type default)
			)
			(layer "F.SilkS")
		)
		(fp_line
			(start -0.508 -0.9398)
			(end -0.508 0.9398)
			(stroke
				(width 0.1524)
				(type default)
			)
			(layer "F.SilkS")
		)
		(fp_rect
			(start -0.508 0.9398)
			(end 0.508 -0.9398)
			(stroke
				(width 0)
				(type default)
			)
			(fill no)
			(layer "F.CrtYd")
		)
		(fp_rect
			(start -0.508 0.9398)
			(end 0.508 -0.9398)
			(stroke
				(width 0)
				(type default)
			)
			(fill no)
			(layer "F.Fab")
		)
		(pad "1" smd custom
			(at 0 -0.4445 90)
			(size 0.1397 0.1397)
			(layers "F.Cu" "F.Mask" "F.Paste")
			(net "LS_EN_U40")
			(options
				(clearance outline)
				(anchor circle)
			)
			(primitives
				(gr_poly
					(pts
						(arc
							(start -0.1778 -0.2794)
							(mid -0.249642 -0.249642)
							(end -0.2794 -0.1778)
						)
						(arc
							(start -0.2794 0.1778)
							(mid -0.249642 0.249642)
							(end -0.1778 0.2794)
						)
						(arc
							(start 0.1778 0.2794)
							(mid 0.249642 0.249642)
							(end 0.2794 0.1778)
						)
						(arc
							(start 0.2794 -0.1778)
							(mid 0.249642 -0.249642)
							(end 0.1778 -0.2794)
						)
					)
					(width 0)
					(fill yes)
				)
			)
		)
		(pad "2" smd custom
			(at 0 0.4445 90)
			(size 0.1397 0.1397)
			(layers "F.Cu" "F.Mask" "F.Paste")
			(net "VREF3")
			(options
				(clearance outline)
				(anchor circle)
			)
			(primitives
				(gr_poly
					(pts
						(arc
							(start -0.1778 -0.2794)
							(mid -0.249642 -0.249642)
							(end -0.2794 -0.1778)
						)
						(arc
							(start -0.2794 0.1778)
							(mid -0.249642 0.249642)
							(end -0.1778 0.2794)
						)
						(arc
							(start 0.1778 0.2794)
							(mid 0.249642 0.249642)
							(end 0.2794 0.1778)
						)
						(arc
							(start 0.2794 -0.1778)
							(mid 0.249642 -0.249642)
							(end 0.1778 -0.2794)
						)
					)
					(width 0)
					(fill yes)
				)
			)
		)
	)
	(footprint ""
		(layer "F.Cu")
		(at 55.937658 -17.40281 180)
		(property "Reference" "R587"
			(at 0 0 180)
			(layer "F.SilkS")
			(hide yes)
			(effects
				(font
					(size 1.27 1.27)
				)
			)
		)
		(property "Value" "10KR2F-2-GP"
			(at 0.064008 -3.993896 180)
			(unlocked yes)
			(layer "F.Fab")
			(hide yes)
			(effects
				(font
					(size 1.016 1.016)
					(thickness 0.1524)
				)
			)
		)
		(property "Device Type" "R402H16"
			(at 0.064008 -5.517896 180)
			(unlocked yes)
			(layer "F.Fab")
			(hide yes)
			(effects
				(font
					(size 1.016 1.016)
					(thickness 0.1524)
				)
			)
		)
		(duplicate_pad_numbers_are_jumpers no)
		(fp_line
			(start 0.508 -0.9398)
			(end -0.508 -0.9398)
			(stroke
				(width 0.1524)
				(type default)
			)
			(layer "F.SilkS")
		)
		(fp_line
			(start -0.508 -0.9398)
			(end -0.508 0.9398)
			(stroke
				(width 0.1524)
				(type default)
			)
			(layer "F.SilkS")
		)
		(fp_rect
			(start -0.508 0.9398)
			(end 0.508 -0.9398)
			(stroke
				(width 0)
				(type default)
			)
			(fill no)
			(layer "F.CrtYd")
		)
		(fp_rect
			(start -0.508 0.9398)
			(end 0.508 -0.9398)
			(stroke
				(width 0)
				(type default)
			)
			(fill no)
			(layer "F.Fab")
		)
		(pad "1" smd custom
			(at 0 -0.4445 180)
			(size 0.1397 0.1397)
			(layers "F.Cu" "F.Mask" "F.Paste")
			(net "P3V3_DPB")
			(options
				(clearance outline)
				(anchor circle)
			)
			(primitives
				(gr_poly
					(pts
						(arc
							(start -0.1778 -0.2794)
							(mid -0.249642 -0.249642)
							(end -0.2794 -0.1778)
						)
						(arc
							(start -0.2794 0.1778)
							(mid -0.249642 0.249642)
							(end -0.1778 0.2794)
						)
						(arc
							(start 0.1778 0.2794)
							(mid 0.249642 0.249642)
							(end 0.2794 0.1778)
						)
						(arc
							(start 0.2794 -0.1778)
							(mid 0.249642 -0.249642)
							(end 0.1778 -0.2794)
						)
					)
					(width 0)
					(fill yes)
				)
			)
		)
		(pad "2" smd custom
			(at 0 0.4445 180)
			(size 0.1397 0.1397)
			(layers "F.Cu" "F.Mask" "F.Paste")
			(net "U47_OE")
			(options
				(clearance outline)
				(anchor circle)
			)
			(primitives
				(gr_poly
					(pts
						(arc
							(start -0.1778 -0.2794)
							(mid -0.249642 -0.249642)
							(end -0.2794 -0.1778)
						)
						(arc
							(start -0.2794 0.1778)
							(mid -0.249642 0.249642)
							(end -0.1778 0.2794)
						)
						(arc
							(start 0.1778 0.2794)
							(mid 0.249642 0.249642)
							(end 0.2794 0.1778)
						)
						(arc
							(start 0.2794 -0.1778)
							(mid 0.249642 -0.249642)
							(end 0.1778 -0.2794)
						)
					)
					(width 0)
					(fill yes)
				)
			)
		)
	)
	(footprint ""
		(layer "F.Cu")
		(at 8.382 -39.497 180)
		(property "Reference" "R526"
			(at 0 0 180)
			(layer "F.SilkS")
			(hide yes)
			(effects
				(font
					(size 1.27 1.27)
				)
			)
		)
		(property "Value" "10R5F-1-GP"
			(at 0 -8.9535 180)
			(unlocked yes)
			(layer "F.Fab")
			(hide yes)
			(effects
				(font
					(size 1.27 1.016)
					(thickness 0.1524)
				)
			)
		)
		(property "Device Type" "R805H24"
			(at 0 -10.6299 180)
			(unlocked yes)
			(layer "F.Fab")
			(hide yes)
			(effects
				(font
					(size 1.27 1.016)
					(thickness 0.1524)
				)
			)
		)
		(duplicate_pad_numbers_are_jumpers no)
		(fp_line
			(start 0.889 1.7018)
			(end 0.889 -0.508)
			(stroke
				(width 0.1524)
				(type default)
			)
			(layer "F.SilkS")
		)
		(fp_line
			(start 0.889 -1.7018)
			(end 0.889 -0.381)
			(stroke
				(width 0.1524)
				(type default)
			)
			(layer "F.SilkS")
		)
		(fp_line
			(start 0.889 -1.7018)
			(end -0.889 -1.7018)
			(stroke
				(width 0.1524)
				(type default)
			)
			(layer "F.SilkS")
		)
		(fp_line
			(start -0.889 1.7018)
			(end 0.889 1.7018)
			(stroke
				(width 0.1524)
				(type default)
			)
			(layer "F.SilkS")
		)
		(fp_line
			(start -0.889 0.0762)
			(end -0.889 1.7018)
			(stroke
				(width 0.1524)
				(type default)
			)
			(layer "F.SilkS")
		)
		(fp_line
			(start -0.889 -1.7018)
			(end -0.889 0.2794)
			(stroke
				(width 0.1524)
				(type default)
			)
			(layer "F.SilkS")
		)
		(fp_poly
			(pts
				(xy 0.9652 -1.778) (xy 0.9652 1.778) (xy -0.9652 1.778) (xy -0.9652 -1.778)
			)
			(stroke
				(width 0)
				(type default)
			)
			(fill no)
			(layer "F.CrtYd")
		)
		(fp_rect
			(start -0.9652 1.778)
			(end 0.9652 -1.778)
			(stroke
				(width 0)
				(type default)
			)
			(fill no)
			(layer "F.Fab")
		)
		(pad "1" smd rect
			(at 0 -0.9652 180)
			(size 1.397 1.143)
			(layers "F.Cu" "F.Mask" "F.Paste")
			(net "MB0_12V_CTRL_GATE1")
		)
		(pad "2" smd rect
			(at 0 0.9652 180)
			(size 1.397 1.143)
			(layers "F.Cu" "F.Mask" "F.Paste")
			(net "MB0_CM_GATE_R")
		)
	)
	(footprint ""
		(layer "F.Cu")
		(at 152.155398 -72.140318 -90)
		(property "Reference" "C532"
			(at 0 0 270)
			(layer "F.SilkS")
			(hide yes)
			(effects
				(font
					(size 1.27 1.27)
				)
			)
		)
		(property "Value" "SCD1U16V2KX-3GP"
			(at 1.1811 -2.7051 270)
			(unlocked yes)
			(layer "F.Fab")
			(hide yes)
			(effects
				(font
					(size 1.016 1.016)
					(thickness 0.1524)
				)
			)
		)
		(property "Device Type" "C402H22"
			(at 1.1811 -4.2291 270)
			(unlocked yes)
			(layer "F.Fab")
			(hide yes)
			(effects
				(font
					(size 1.016 1.016)
					(thickness 0.1524)
				)
			)
		)
		(duplicate_pad_numbers_are_jumpers no)
		(fp_rect
			(start -0.4318 0.9525)
			(end 0.4318 -0.9525)
			(stroke
				(width 0)
				(type default)
			)
			(fill no)
			(layer "F.CrtYd")
		)
		(fp_rect
			(start -0.4318 0.9525)
			(end 0.4318 -0.9525)
			(stroke
				(width 0)
				(type default)
			)
			(fill no)
			(layer "F.Fab")
		)
		(pad "1" smd custom
			(at 0 -0.4445 270)
			(size 0.1524 0.1524)
			(layers "F.Cu" "F.Mask" "F.Paste")
			(net "P1V8_C_SENSE")
			(options
				(clearance outline)
				(anchor circle)
			)
			(primitives
				(gr_poly
					(pts
						(arc
							(start 0.3048 -0.2032)
							(mid 0.275042 -0.275042)
							(end 0.2032 -0.3048)
						)
						(arc
							(start -0.2032 -0.3048)
							(mid -0.275042 -0.275042)
							(end -0.3048 -0.2032)
						)
						(arc
							(start -0.3048 0.2032)
							(mid -0.275042 0.275042)
							(end -0.2032 0.3048)
						)
						(arc
							(start 0.2032 0.3048)
							(mid 0.275042 0.275042)
							(end 0.3048 0.2032)
						)
					)
					(width 0)
					(fill yes)
				)
			)
		)
		(pad "2" smd custom
			(at 0 0.4445 270)
			(size 0.1524 0.1524)
			(layers "F.Cu" "F.Mask" "F.Paste")
			(net "GND")
			(options
				(clearance outline)
				(anchor circle)
			)
			(primitives
				(gr_poly
					(pts
						(arc
							(start 0.3048 -0.2032)
							(mid 0.275042 -0.275042)
							(end 0.2032 -0.3048)
						)
						(arc
							(start -0.2032 -0.3048)
							(mid -0.275042 -0.275042)
							(end -0.3048 -0.2032)
						)
						(arc
							(start -0.3048 0.2032)
							(mid -0.275042 0.275042)
							(end -0.2032 0.3048)
						)
						(arc
							(start 0.2032 0.3048)
							(mid 0.275042 0.275042)
							(end 0.3048 0.2032)
						)
					)
					(width 0)
					(fill yes)
				)
			)
		)
	)
	(footprint ""
		(layer "F.Cu")
		(at 185.138822 -84.046568 90)
		(property "Reference" "TC7"
			(at 0 0 90)
			(layer "F.SilkS")
			(hide yes)
			(effects
				(font
					(size 1.27 1.27)
				)
			)
		)
		(property "Value" "SE470UF2VDM-GP"
			(at 0 -9.6012 90)
			(unlocked yes)
			(layer "F.Fab")
			(hide yes)
			(effects
				(font
					(size 1.016 1.016)
					(thickness 0.1524)
				)
			)
		)
		(property "Device Type" "CT7343H83"
			(at 0 -11.1252 90)
			(unlocked yes)
			(layer "F.Fab")
			(hide yes)
			(effects
				(font
					(size 1.016 1.016)
					(thickness 0.1524)
				)
			)
		)
		(duplicate_pad_numbers_are_jumpers no)
		(fp_line
			(start 2.286 -4.8768)
			(end -2.286 -4.8768)
			(stroke
				(width 0.1524)
				(type default)
			)
			(layer "F.SilkS")
		)
		(fp_line
			(start -2.286 -4.8768)
			(end -2.286 -2.032)
			(stroke
				(width 0.1524)
				(type default)
			)
			(layer "F.SilkS")
		)
		(fp_line
			(start 2.1082 -4.699)
			(end -2.1082 -4.699)
			(stroke
				(width 0.508)
				(type default)
			)
			(layer "F.SilkS")
		)
		(fp_line
			(start 2.286 -2.032)
			(end 2.286 -4.8768)
			(stroke
				(width 0.1524)
				(type default)
			)
			(layer "F.SilkS")
		)
		(fp_line
			(start 2.286 2.032)
			(end 2.286 4.8768)
			(stroke
				(width 0.1524)
				(type default)
			)
			(layer "F.SilkS")
		)
		(fp_line
			(start 2.286 4.8768)
			(end -2.286 4.8768)
			(stroke
				(width 0.1524)
				(type default)
			)
			(layer "F.SilkS")
		)
		(fp_line
			(start -2.286 4.8768)
			(end -2.286 2.032)
			(stroke
				(width 0.1524)
				(type default)
			)
			(layer "F.SilkS")
		)
		(fp_rect
			(start -2.1463 3.6449)
			(end 2.1463 -3.6449)
			(stroke
				(width 0)
				(type default)
			)
			(fill no)
			(layer "F.CrtYd")
		)
		(fp_poly
			(pts
				(xy -2.54 4.953) (xy -2.54 4.2926) (xy -3.81 4.2926) (xy -3.81 -4.2926) (xy -2.54 -4.2926) (xy -2.54 -4.953)
				(xy 2.54 -4.953) (xy 2.54 -4.2926) (xy 3.81 -4.2926) (xy 3.81 -1.6256) (xy 2.1463 -1.6256) (xy 2.1463 -3.6449)
				(xy -2.1463 -3.6449) (xy -2.1463 3.6449) (xy 2.1463 3.6449) (xy 2.1463 -1.6129) (xy 3.81 -1.6129)
				(xy 3.81 4.2926) (xy 2.54 4.2926) (xy 2.54 4.953)
			)
			(stroke
				(width 0)
				(type default)
			)
			(fill no)
			(layer "F.CrtYd")
		)
		(fp_rect
			(start 2.54 4.2926)
			(end 3.81 -4.2926)
			(stroke
				(width 0)
				(type default)
			)
			(fill no)
			(layer "F.Fab")
		)
		(fp_rect
			(start -3.81 4.2926)
			(end -2.54 -4.2926)
			(stroke
				(width 0)
				(type default)
			)
			(fill no)
			(layer "F.Fab")
		)
		(fp_rect
			(start -2.54 4.953)
			(end 2.54 -4.953)
			(stroke
				(width 0)
				(type default)
			)
			(fill no)
			(layer "F.Fab")
		)
		(pad "1" smd rect
			(at 0 -3.1496 90)
			(size 2.413 2.286)
			(layers "F.Cu" "F.Mask" "F.Paste")
			(net "P0V975")
		)
		(pad "2" smd rect
			(at 0 3.1496 90)
			(size 2.413 2.286)
			(layers "F.Cu" "F.Mask" "F.Paste")
			(net "GND")
		)
		(zone
			(layer "F.Cu")
			(hatch none 0.5)
			(connect_pads
				(clearance 0)
			)
			(min_thickness 0.25)
			(keepout
				(tracks allowed)
				(vias not_allowed)
				(pads allowed)
				(copperpour not_allowed)
				(footprints allowed)
			)
			(placement
				(enabled no)
				(sheetname "")
			)
			(fill
				(thermal_gap 0.5)
				(thermal_bridge_width 0.5)
				(island_removal_mode 0)
			)
			(polygon
				(pts
					(xy 183.449722 -85.557868) (xy 180.541422 -85.557868) (xy 180.541422 -82.535268) (xy 183.437022 -82.535268)
					(xy 183.767222 -82.535268) (xy 183.767222 -85.557868)
				)
			)
		)
		(zone
			(layer "F.Cu")
			(hatch none 0.5)
			(connect_pads
				(clearance 0)
			)
			(min_thickness 0.25)
			(keepout
				(tracks allowed)
				(vias not_allowed)
				(pads allowed)
				(copperpour not_allowed)
				(footprints allowed)
			)
			(placement
				(enabled no)
				(sheetname "")
			)
			(fill
				(thermal_gap 0.5)
				(thermal_bridge_width 0.5)
				(island_removal_mode 0)
			)
			(polygon
				(pts
					(xy 189.736222 -82.535268) (xy 189.736222 -85.557868) (xy 186.840622 -85.557868) (xy 186.510422 -85.557868)
					(xy 186.510422 -82.535268) (xy 186.840622 -82.535268)
				)
			)
		)
	)
)
